FILE_TYPE = CONNECTIVITY;
{Allegro Design Entry HDL 17.2-2016 S081 (4005846) 1/11/2022}
"PAGE_NUMBER" = 53;
0"NC";
1"P3V3_AUX\g";
2"P5V_AUX\g";
3"P3V3_AUX\g";
4"P2V5_AUX\g";
5"GND\g";
6"GND\g";
7"GND\g";
8"GND\g";
9"GND\g";
10"PWRGD_P3V3_AUX_R2";
11"PWRGD_P2V5_AUX_R";
12"PWRGD_P3V3_AUX";
13"PWRGD_P2V5_AUX";
14"PWRGD_P2V5_AUX_R3";
15"U39_ADJ";
%"UNIVERSAL_GND"
"1","(-1650,775)","0","logical_power","I10";
;
CDS_LIB"logical_power"
HDL_POWER"GND";
"A"9;
%"UNIVERSAL_GND"
"1","(-100,-400)","0","logical_power","I16";
;
CDS_LIB"logical_power"
HDL_POWER"GND";
"A"8;
%"VCCAUX15"
"1","(-1650,1525)","0","logical_power","I2";
;
HDL_POWER"P5V_AUX"
CDS_LIB"logical_power";
"A"2;
%"UNIVERSAL_GND"
"1","(1250,-175)","0","logical_power","I26";
;
CDS_LIB"logical_power"
HDL_POWER"GND";
"A"7;
%"VCCAUX15"
"1","(2400,650)","0","logical_power","I29";
;
HDL_POWER"P2V5_AUX"
CDS_LIB"logical_power";
"A"4;
%"VCCAUX15"
"1","(-1375,275)","0","logical_power","I45";
;
HDL_POWER"P3V3_AUX"
CDS_LIB"logical_power";
"A"1;
%"VCCAUX15"
"1","(400,1700)","0","logical_power","I48";
;
HDL_POWER"P3V3_AUX"
CDS_LIB"logical_power";
"A"3;
%"UNIVERSAL_GND"
"1","(400,950)","0","logical_power","I50";
;
CDS_LIB"logical_power"
HDL_POWER"GND";
"A"6;
%"Q_RES"
"1","(-2525,-125)","0","pure_quanta","I58";
;
VALUE"0"
MATERIAL"CHIP"
PACK_TYPE"0402LF"
PART_NUMBER"CS00002JB13"
CDS_LIB"pure_quanta"
WATTAGE"1/16W"
TOLERANCE"5%"
LOCATION"R35"
$SEC"1"
CDS_SEC"1";
"B"
$PN"2"11;
"A"
$PN"1"13;
%"RT9059GQW"
"1","(-650,375)","0","pure_quanta","I60";
;
PART_TYPE"SMLF"
VALUE"RT9059GQW"
MATERIAL"IC"
PART_NUMBER"AL009059000"
PIN_NAMES_ROTATE"True"
CDS_LMAN_SYM_OUTLINE"-250,550,250,-550"
CDS_LIB"pure_quanta"
LOCATION"U39"
$SEC"1"
CDS_SEC"1";
"VIN3"
$PN"9"3;
"VIN2"
$PN"8"3;
"VOUT3"
$PN"3"4;
"VOUT2"
$PN"2"4;
"EP"
$PN"TH"8;
"VDD"
$PN"10"2;
"VIN1"
$PN"7"3;
"VOUT1"
$PN"1"4;
"ADJ"
$PN"4"15;
"EN"
$PN"6"10;
"PGOOD"
$PN"5"11;
%"Q_RES"
"2","(325,-175)","0","pure_quanta","I61";
;
VALUE"12K"
TOLERANCE"1%"
WATTAGE"1/16W"
MATERIAL"CHIP"
PART_NUMBER"CS31202FB04"
PACK_TYPE"0402LF"
CDS_LIB"pure_quanta"
LOCATION"R830"
$SEC"1"
CDS_SEC"1";
"A"
$PN"1"15;
"B"
$PN"2"8;
%"Q_RES"
"2","(325,250)","0","pure_quanta","I62";
;
VALUE"25.5K"
TOLERANCE"1%"
PACK_TYPE"0402LF"
WATTAGE"1/16W"
MATERIAL"CHIP"
PART_NUMBER"CS32552FB06"
CDS_LIB"pure_quanta"
LOCATION"R829"
$SEC"1"
CDS_SEC"1";
"A"
$PN"1"4;
"B"
$PN"2"15;
%"UNIVERSAL_GND"
"1","(-2025,-525)","0","logical_power","I63";
;
CDS_LIB"logical_power"
HDL_POWER"GND";
"A"5;
%"Q_CAP"
"1","(-2025,-325)","0","pure_quanta","I64";
;
PART_NUMBER"CH30106KB19"
PACK_TYPE"C0402"
TOLERANCE"10%"
VOLTAGE"50V"
VALUE"0.001UF"
MATERIAL"EMPTY"
CDS_LIB"pure_quanta"
LOCATION"C153"
$SEC"1"
CDS_SEC"1";
"B"
$PN"2"5;
"A"
$PN"1"11;
%"Q_RES"
"1","(-2000,425)","0","pure_quanta","I65";
;
PACK_TYPE"0402LF"
PART_NUMBER"CS00002JB13"
TOLERANCE"5%"
MATERIAL"CHIP"
VALUE"0"
WATTAGE"1/16W"
CDS_LIB"pure_quanta"
LOCATION"R382"
$SEC"1"
CDS_SEC"1";
"B"
$PN"2"10;
"A"
$PN"1"12;
%"Q_CAP"
"1","(-1650,1100)","0","pure_quanta","I67";
;
VOLTAGE"25V"
MATERIAL"X6S"
TOLERANCE"10%"
PART_NUMBER"CH5104KEB02"
PACK_TYPE"C0402"
VALUE"1UF"
CDS_LIB"pure_quanta"
$LOCATION"C287"
CDS_LOCATION"C287"
$SEC"1"
CDS_SEC"1";
"B"
$PN"2"9;
"A"
$PN"1"2;
%"Q_RES"
"2","(-1375,100)","0","pure_quanta","I68";
;
PACK_TYPE"0402LF"
MATERIAL"CHIP"
TOLERANCE"1%"
PART_NUMBER"CS31002FB08"
WATTAGE"1/16W"
VALUE"10K"
CDS_LIB"pure_quanta"
$LOCATION"R403"
CDS_LOCATION"R403"
$SEC"1"
CDS_SEC"1";
"A"
$PN"1"1;
"B"
$PN"2"11;
%"Q_CAP"
"1","(1250,250)","0","pure_quanta","I69";
;
PACK_TYPE"C0805"
MATERIAL"X6S"
VALUE"10UF"
PART_NUMBER"CH6104KEA00"
TOLERANCE"10%"
VOLTAGE"25V"
CDS_LIB"pure_quanta"
$LOCATION"C289"
CDS_LOCATION"C289"
$SEC"1"
CDS_SEC"1";
"B"
$PN"2"7;
"A"
$PN"1"4;
%"Q_CAP"
"1","(1900,250)","0","pure_quanta","I70";
;
PACK_TYPE"0402"
VALUE"0.1UF"
PART_NUMBER"CH4104K1B00"
VOLTAGE"25V"
TOLERANCE"10%"
MATERIAL"X7R"
CDS_LIB"pure_quanta"
$LOCATION"C291"
CDS_LOCATION"C291"
$SEC"1"
CDS_SEC"1";
"B"
$PN"2"7;
"A"
$PN"1"4;
%"Q_CAP"
"1","(400,1275)","0","pure_quanta","I71";
;
MATERIAL"X6S"
TOLERANCE"10%"
VOLTAGE"25V"
VALUE"10UF"
PACK_TYPE"C0805"
PART_NUMBER"CH6104KEA00"
CDS_LIB"pure_quanta"
$LOCATION"C288"
CDS_LOCATION"C288"
$SEC"1"
CDS_SEC"1";
"B"
$PN"2"6;
"A"
$PN"1"3;
%"Q_RES"
"1","(-3050,75)","0","pure_quanta","I72";
;
VALUE"0"
MATERIAL"EMPTY"
PART_NUMBER"CS00002JB13"
PACK_TYPE"0402LF"
CDS_LIB"pure_quanta"
WATTAGE"1/16W"
TOLERANCE"5%"
$LOCATION"R873"
CDS_LOCATION"R873"
$SEC"1"
CDS_SEC"1";
"B"
$PN"2"13;
"A"
$PN"1"14;
END.
